# ZAIUS-LV_CARD-EVT1-X00-BOM-X01_20160825.xls — DEPOP_GA (bom)
| FOXCONN TECHNOLOGY GROUP |  |  |  |  |  |  |  |  |  |  |  |  |
| BILL OF MATERIAL |  |  |  |  |  |  |  |  |  |  |  |  |
| REV OF  BOM |  | CUSTOMER | DELL |  | CUSTOMER P/N |  | PRODUCT CODE |  | PWA  REV |  | DATE |  |
| Sourcing (Single/Sole/Multi) | Critical Commodity (Y or N) | Component Class (1, 2, other) | Dell PSL (Y or N) | Item Number | Foxconn P/N | Dell P/N | Part Description | Manufacturer  Full Name | Manufacturer  Part Number | Qty | RoHS Status | Location |
